(kicad_pcb
	(version 20260206)
	(generator "pcbnew")
	(generator_version "10.0")
	(general
		(thickness 1.6)
		(legacy_teardrops no)
	)
	(paper "A4")
	(title_block
		(title "Bryce Canyon_SCC_16316-1_OCP.brd")
		(comment 1 "Bryce Canyon / footprints 824-828 of 1561")
	)
	(layers
		(0 "F.Cu" signal "TOP")
		(4 "In1.Cu" signal "L2GND")
		(6 "In2.Cu" signal "L3")
		(8 "In3.Cu" signal "L4VCC")
		(10 "In4.Cu" signal "L5VCC")
		(12 "In5.Cu" signal "L6")
		(14 "In6.Cu" signal "L7GND")
		(2 "B.Cu" signal "BOTTOM")
		(9 "F.Adhes" user "F.Adhesive")
		(11 "B.Adhes" user "B.Adhesive")
		(13 "F.Paste" user "Package Geometry/Pastemask Top")
		(15 "B.Paste" user "Package Geometry/Pastemask Bottom")
		(5 "F.SilkS" user "Ref Des/Silkscreen Top")
		(7 "B.SilkS" user "Ref Des/Silkscreen Bottom")
		(1 "F.Mask" user "Board Geometry/Soldermask Top")
		(3 "B.Mask" user "Board Geometry/Soldermask Bottom")
		(17 "Dwgs.User" user "User.Drawings")
		(19 "Cmts.User" user "User.Comments")
		(21 "Eco1.User" user "User.Eco1")
		(23 "Eco2.User" user "User.Eco2")
		(25 "Edge.Cuts" user "Board Geometry/Outline")
		(27 "Margin" user)
		(31 "F.CrtYd" user "Package Geometry/Place Bound Top")
		(29 "B.CrtYd" user "Package Geometry/Place Bound Bottom")
		(35 "F.Fab" user "Ref Des/Assembly Top")
		(33 "B.Fab" user "Ref Des/Assembly Bottom")
	)
	(footprint ""
		(layer "B.Cu")
		(at 193.60642 -67.277234 -90)
		(property "Reference" "U18"
			(at 0 0 90)
			(layer "B.SilkS")
			(hide yes)
			(effects
				(font
					(size 1.27 1.27)
				)
				(justify mirror)
			)
		)
		(property "Value" "S29GL128S10TFIV20-GP"
			(at 0.1778 -20.32 270)
			(unlocked yes)
			(layer "B.Fab")
			(hide yes)
			(effects
				(font
					(size 1.016 1.016)
					(thickness 0.1524)
				)
				(justify mirror)
			)
		)
		(property "Device Type" "TSOP56-1H48"
			(at 0.1778 -22.225 270)
			(unlocked yes)
			(layer "B.Fab")
			(hide yes)
			(effects
				(font
					(size 1.016 1.016)
					(thickness 0.1524)
				)
				(justify mirror)
			)
		)
		(duplicate_pad_numbers_are_jumpers no)
		(fp_line
			(start -6.8326 8.5598)
			(end -6.8326 -8.5598)
			(stroke
				(width 0.1524)
				(type default)
			)
			(layer "B.SilkS")
		)
		(fp_line
			(start 7.366 8.5598)
			(end 7.366 10.795)
			(stroke
				(width 0.508)
				(type default)
			)
			(layer "B.SilkS")
		)
		(fp_line
			(start 7.5438 8.5598)
			(end -6.8326 8.5598)
			(stroke
				(width 0.1524)
				(type default)
			)
			(layer "B.SilkS")
		)
		(fp_line
			(start 7.112 0)
			(end 7.5438 0.4318)
			(stroke
				(width 0.1524)
				(type default)
			)
			(layer "B.SilkS")
		)
		(fp_line
			(start 7.5438 -0.4318)
			(end 7.112 0)
			(stroke
				(width 0.1524)
				(type default)
			)
			(layer "B.SilkS")
		)
		(fp_line
			(start -6.8326 -8.5598)
			(end 7.5438 -8.5598)
			(stroke
				(width 0.1524)
				(type default)
			)
			(layer "B.SilkS")
		)
		(fp_line
			(start 7.5438 -8.5598)
			(end 7.5438 8.5598)
			(stroke
				(width 0.1524)
				(type default)
			)
			(layer "B.SilkS")
		)
		(fp_poly
			(pts
				(xy 7.62 11.049) (xy -7.62 11.049) (xy -7.62 -11.049) (xy 7.62 -11.049)
			)
			(stroke
				(width 0)
				(type default)
			)
			(fill no)
			(layer "B.CrtYd")
		)
		(fp_poly
			(pts
				(xy 7.62 -11.049) (xy -7.62 -11.049) (xy -7.62 11.049) (xy 7.62 11.049)
			)
			(stroke
				(width 0)
				(type default)
			)
			(fill no)
			(layer "B.Fab")
		)
		(pad "1" smd rect
			(at 6.75005 9.6139 90)
			(size 0.3048 1.524)
			(layers "B.Cu" "B.Mask" "B.Paste")
			(net "Net_766")
		)
		(pad "2" smd rect
			(at 6.24967 9.6139 90)
			(size 0.3048 1.524)
			(layers "B.Cu" "B.Mask" "B.Paste")
			(net "XM_ADDR_23")
		)
		(pad "3" smd rect
			(at 5.75056 9.6139 90)
			(size 0.3048 1.524)
			(layers "B.Cu" "B.Mask" "B.Paste")
			(net "XM_ADDR_16")
		)
		(pad "4" smd rect
			(at 5.25018 9.6139 90)
			(size 0.3048 1.524)
			(layers "B.Cu" "B.Mask" "B.Paste")
			(net "XM_ADDR_15")
		)
		(pad "5" smd rect
			(at 4.7498 9.6139 90)
			(size 0.3048 1.524)
			(layers "B.Cu" "B.Mask" "B.Paste")
			(net "XM_ADDR_14")
		)
		(pad "6" smd rect
			(at 4.24942 9.6139 90)
			(size 0.3048 1.524)
			(layers "B.Cu" "B.Mask" "B.Paste")
			(net "XM_ADDR_13")
		)
		(pad "7" smd rect
			(at 3.75031 9.6139 90)
			(size 0.3048 1.524)
			(layers "B.Cu" "B.Mask" "B.Paste")
			(net "XM_ADDR_12")
		)
		(pad "8" smd rect
			(at 3.24993 9.6139 90)
			(size 0.3048 1.524)
			(layers "B.Cu" "B.Mask" "B.Paste")
			(net "XM_ADDR_11")
		)
		(pad "9" smd rect
			(at 2.74955 9.6139 90)
			(size 0.3048 1.524)
			(layers "B.Cu" "B.Mask" "B.Paste")
			(net "XM_ADDR_10")
		)
		(pad "10" smd rect
			(at 2.25044 9.6139 90)
			(size 0.3048 1.524)
			(layers "B.Cu" "B.Mask" "B.Paste")
			(net "XM_ADDR_9")
		)
		(pad "11" smd rect
			(at 1.75006 9.6139 90)
			(size 0.3048 1.524)
			(layers "B.Cu" "B.Mask" "B.Paste")
			(net "XM_ADDR_20")
		)
		(pad "12" smd rect
			(at 1.24968 9.6139 90)
			(size 0.3048 1.524)
			(layers "B.Cu" "B.Mask" "B.Paste")
			(net "XM_ADDR_21")
		)
		(pad "13" smd rect
			(at 0.75057 9.6139 90)
			(size 0.3048 1.524)
			(layers "B.Cu" "B.Mask" "B.Paste")
			(net "XM_WE_N")
		)
		(pad "14" smd rect
			(at 0.25019 9.6139 90)
			(size 0.3048 1.524)
			(layers "B.Cu" "B.Mask" "B.Paste")
			(net "XM_F_RST_N")
		)
		(pad "15" smd rect
			(at -0.25019 9.6139 90)
			(size 0.3048 1.524)
			(layers "B.Cu" "B.Mask" "B.Paste")
			(net "XM_ADDR_22")
		)
		(pad "16" smd rect
			(at -0.75057 9.6139 90)
			(size 0.3048 1.524)
			(layers "B.Cu" "B.Mask" "B.Paste")
			(net "IOC_WP_N")
		)
		(pad "17" smd rect
			(at -1.24968 9.6139 90)
			(size 0.3048 1.524)
			(layers "B.Cu" "B.Mask" "B.Paste")
			(net "Net_761")
		)
		(pad "18" smd rect
			(at -1.75006 9.6139 90)
			(size 0.3048 1.524)
			(layers "B.Cu" "B.Mask" "B.Paste")
			(net "XM_ADDR_19")
		)
		(pad "19" smd rect
			(at -2.25044 9.6139 90)
			(size 0.3048 1.524)
			(layers "B.Cu" "B.Mask" "B.Paste")
			(net "XM_ADDR_18")
		)
		(pad "20" smd rect
			(at -2.74955 9.6139 90)
			(size 0.3048 1.524)
			(layers "B.Cu" "B.Mask" "B.Paste")
			(net "XM_ADDR_8")
		)
		(pad "21" smd rect
			(at -3.24993 9.6139 90)
			(size 0.3048 1.524)
			(layers "B.Cu" "B.Mask" "B.Paste")
			(net "XM_ADDR_7")
		)
		(pad "22" smd rect
			(at -3.75031 9.6139 90)
			(size 0.3048 1.524)
			(layers "B.Cu" "B.Mask" "B.Paste")
			(net "XM_ADDR_6")
		)
		(pad "23" smd rect
			(at -4.24942 9.6139 90)
			(size 0.3048 1.524)
			(layers "B.Cu" "B.Mask" "B.Paste")
			(net "XM_ADDR_5")
		)
		(pad "24" smd rect
			(at -4.7498 9.6139 90)
			(size 0.3048 1.524)
			(layers "B.Cu" "B.Mask" "B.Paste")
			(net "XM_ADDR_4")
		)
		(pad "25" smd rect
			(at -5.25018 9.6139 90)
			(size 0.3048 1.524)
			(layers "B.Cu" "B.Mask" "B.Paste")
			(net "XM_ADDR_3")
		)
		(pad "26" smd rect
			(at -5.75056 9.6139 90)
			(size 0.3048 1.524)
			(layers "B.Cu" "B.Mask" "B.Paste")
			(net "XM_ADDR_2")
		)
		(pad "27" smd rect
			(at -6.24967 9.6139 90)
			(size 0.3048 1.524)
			(layers "B.Cu" "B.Mask" "B.Paste")
			(net "Net_762")
		)
		(pad "28" smd rect
			(at -6.75005 9.6139 90)
			(size 0.3048 1.524)
			(layers "B.Cu" "B.Mask" "B.Paste")
			(net "Net_763")
		)
		(pad "29" smd rect
			(at -6.75005 -9.6139 90)
			(size 0.3048 1.524)
			(layers "B.Cu" "B.Mask" "B.Paste")
			(net "P1V8_C")
		)
		(pad "30" smd rect
			(at -6.24967 -9.6139 90)
			(size 0.3048 1.524)
			(layers "B.Cu" "B.Mask" "B.Paste")
			(net "Net_760")
		)
		(pad "31" smd rect
			(at -5.75056 -9.6139 90)
			(size 0.3048 1.524)
			(layers "B.Cu" "B.Mask" "B.Paste")
			(net "XM_ADDR_1")
		)
		(pad "32" smd rect
			(at -5.25018 -9.6139 90)
			(size 0.3048 1.524)
			(layers "B.Cu" "B.Mask" "B.Paste")
			(net "XM_NOR_CS_N")
		)
		(pad "33" smd rect
			(at -4.7498 -9.6139 90)
			(size 0.3048 1.524)
			(layers "B.Cu" "B.Mask" "B.Paste")
			(net "GND")
		)
		(pad "34" smd rect
			(at -4.24942 -9.6139 90)
			(size 0.3048 1.524)
			(layers "B.Cu" "B.Mask" "B.Paste")
			(net "XM_OE_N")
		)
		(pad "35" smd rect
			(at -3.75031 -9.6139 90)
			(size 0.3048 1.524)
			(layers "B.Cu" "B.Mask" "B.Paste")
			(net "XM_DATA_0")
		)
		(pad "36" smd rect
			(at -3.24993 -9.6139 90)
			(size 0.3048 1.524)
			(layers "B.Cu" "B.Mask" "B.Paste")
			(net "XM_DATA_8")
		)
		(pad "37" smd rect
			(at -2.74955 -9.6139 90)
			(size 0.3048 1.524)
			(layers "B.Cu" "B.Mask" "B.Paste")
			(net "XM_DATA_1")
		)
		(pad "38" smd rect
			(at -2.25044 -9.6139 90)
			(size 0.3048 1.524)
			(layers "B.Cu" "B.Mask" "B.Paste")
			(net "XM_DATA_9")
		)
		(pad "39" smd rect
			(at -1.75006 -9.6139 90)
			(size 0.3048 1.524)
			(layers "B.Cu" "B.Mask" "B.Paste")
			(net "XM_DATA_2")
		)
		(pad "40" smd rect
			(at -1.24968 -9.6139 90)
			(size 0.3048 1.524)
			(layers "B.Cu" "B.Mask" "B.Paste")
			(net "XM_DATA_10")
		)
		(pad "41" smd rect
			(at -0.75057 -9.6139 90)
			(size 0.3048 1.524)
			(layers "B.Cu" "B.Mask" "B.Paste")
			(net "XM_DATA_3")
		)
		(pad "42" smd rect
			(at -0.25019 -9.6139 90)
			(size 0.3048 1.524)
			(layers "B.Cu" "B.Mask" "B.Paste")
			(net "XM_DATA_11")
		)
		(pad "43" smd rect
			(at 0.25019 -9.6139 90)
			(size 0.3048 1.524)
			(layers "B.Cu" "B.Mask" "B.Paste")
			(net "P3V3")
		)
		(pad "44" smd rect
			(at 0.75057 -9.6139 90)
			(size 0.3048 1.524)
			(layers "B.Cu" "B.Mask" "B.Paste")
			(net "XM_DATA_4")
		)
		(pad "45" smd rect
			(at 1.24968 -9.6139 90)
			(size 0.3048 1.524)
			(layers "B.Cu" "B.Mask" "B.Paste")
			(net "XM_DATA_12")
		)
		(pad "46" smd rect
			(at 1.75006 -9.6139 90)
			(size 0.3048 1.524)
			(layers "B.Cu" "B.Mask" "B.Paste")
			(net "XM_DATA_5")
		)
		(pad "47" smd rect
			(at 2.25044 -9.6139 90)
			(size 0.3048 1.524)
			(layers "B.Cu" "B.Mask" "B.Paste")
			(net "XM_DATA_13")
		)
		(pad "48" smd rect
			(at 2.74955 -9.6139 90)
			(size 0.3048 1.524)
			(layers "B.Cu" "B.Mask" "B.Paste")
			(net "XM_DATA_6")
		)
		(pad "49" smd rect
			(at 3.24993 -9.6139 90)
			(size 0.3048 1.524)
			(layers "B.Cu" "B.Mask" "B.Paste")
			(net "XM_DATA_14")
		)
		(pad "50" smd rect
			(at 3.75031 -9.6139 90)
			(size 0.3048 1.524)
			(layers "B.Cu" "B.Mask" "B.Paste")
			(net "XM_DATA_7")
		)
		(pad "51" smd rect
			(at 4.24942 -9.6139 90)
			(size 0.3048 1.524)
			(layers "B.Cu" "B.Mask" "B.Paste")
			(net "XM_DATA_15")
		)
		(pad "52" smd rect
			(at 4.7498 -9.6139 90)
			(size 0.3048 1.524)
			(layers "B.Cu" "B.Mask" "B.Paste")
			(net "GND")
		)
		(pad "53" smd rect
			(at 5.25018 -9.6139 90)
			(size 0.3048 1.524)
			(layers "B.Cu" "B.Mask" "B.Paste")
			(net "IOC_BYTE_N")
		)
		(pad "54" smd rect
			(at 5.75056 -9.6139 90)
			(size 0.3048 1.524)
			(layers "B.Cu" "B.Mask" "B.Paste")
			(net "XM_ADDR_17")
		)
		(pad "55" smd rect
			(at 6.24967 -9.6139 90)
			(size 0.3048 1.524)
			(layers "B.Cu" "B.Mask" "B.Paste")
			(net "Net_764")
		)
		(pad "56" smd rect
			(at 6.75005 -9.6139 90)
			(size 0.3048 1.524)
			(layers "B.Cu" "B.Mask" "B.Paste")
			(net "Net_765")
		)
	)
	(footprint ""
		(layer "B.Cu")
		(at 92.119958 -78.247748)
		(property "Reference" "C208"
			(at 0 0 0)
			(layer "B.SilkS")
			(hide yes)
			(effects
				(font
					(size 1.27 1.27)
				)
				(justify mirror)
			)
		)
		(property "Value" "SC22U6D3V3MX-9-GP-U"
			(at 0 -2.8194 0)
			(unlocked yes)
			(layer "B.Fab")
			(hide yes)
			(effects
				(font
					(size 1.016 1.016)
					(thickness 0.1524)
				)
				(justify mirror)
			)
		)
		(property "Device Type" "C603H40"
			(at 0 -4.3434 0)
			(unlocked yes)
			(layer "B.Fab")
			(hide yes)
			(effects
				(font
					(size 1.016 1.016)
					(thickness 0.1524)
				)
				(justify mirror)
			)
		)
		(duplicate_pad_numbers_are_jumpers no)
		(fp_line
			(start -0.508 0)
			(end 0.508 0)
			(stroke
				(width 0.2032)
				(type default)
			)
			(layer "B.SilkS")
		)
		(fp_rect
			(start 0.5842 1.3335)
			(end -0.5842 -1.3335)
			(stroke
				(width 0)
				(type default)
			)
			(fill no)
			(layer "B.CrtYd")
		)
		(fp_rect
			(start 0.5842 1.3335)
			(end -0.5842 -1.3335)
			(stroke
				(width 0)
				(type default)
			)
			(fill no)
			(layer "B.Fab")
		)
		(pad "1" smd custom
			(at 0 -0.762 180)
			(size 0.2159 0.2159)
			(layers "B.Cu" "B.Mask" "B.Paste")
			(net "SYSPLL_VDDA09")
			(options
				(clearance outline)
				(anchor circle)
			)
			(primitives
				(gr_poly
					(pts
						(arc
							(start -0.3302 0.4318)
							(mid -0.402042 0.402042)
							(end -0.4318 0.3302)
						)
						(arc
							(start -0.4318 -0.3302)
							(mid -0.402042 -0.402042)
							(end -0.3302 -0.4318)
						)
						(arc
							(start 0.3302 -0.4318)
							(mid 0.402042 -0.402042)
							(end 0.4318 -0.3302)
						)
						(arc
							(start 0.4318 0.3302)
							(mid 0.402042 0.402042)
							(end 0.3302 0.4318)
						)
					)
					(width 0)
					(fill yes)
				)
			)
		)
		(pad "2" smd custom
			(at 0 0.762 180)
			(size 0.2159 0.2159)
			(layers "B.Cu" "B.Mask" "B.Paste")
			(net "GND")
			(options
				(clearance outline)
				(anchor circle)
			)
			(primitives
				(gr_poly
					(pts
						(arc
							(start -0.3302 0.4318)
							(mid -0.402042 0.402042)
							(end -0.4318 0.3302)
						)
						(arc
							(start -0.4318 -0.3302)
							(mid -0.402042 -0.402042)
							(end -0.3302 -0.4318)
						)
						(arc
							(start 0.3302 -0.4318)
							(mid 0.402042 -0.402042)
							(end 0.4318 -0.3302)
						)
						(arc
							(start 0.4318 0.3302)
							(mid 0.402042 0.402042)
							(end 0.3302 0.4318)
						)
					)
					(width 0)
					(fill yes)
				)
			)
		)
	)
	(footprint ""
		(layer "B.Cu")
		(at 189.9158 -29.1592 90)
		(property "Reference" "TP74"
			(at 0 0 90)
			(layer "B.SilkS")
			(hide yes)
			(effects
				(font
					(size 1.27 1.27)
				)
				(justify mirror)
			)
		)
		(property "Value" "TPAD28-2-GP"
			(at 0.0127 -1.6637 90)
			(unlocked yes)
			(layer "B.Fab")
			(hide yes)
			(effects
				(font
					(size 1.016 1.016)
					(thickness 0.1524)
				)
				(justify mirror)
			)
		)
		(property "Device Type" "TPAD28"
			(at 0.0127 -3.1877 90)
			(unlocked yes)
			(layer "B.Fab")
			(hide yes)
			(effects
				(font
					(size 1.016 1.016)
					(thickness 0.1524)
				)
				(justify mirror)
			)
		)
		(duplicate_pad_numbers_are_jumpers no)
		(fp_poly
			(pts
				(arc
					(start 0 0.3556)
					(mid 0 -0.3556)
					(end 0 0.3556)
				)
			)
			(stroke
				(width 0)
				(type default)
			)
			(fill no)
			(layer "B.CrtYd")
		)
		(fp_poly
			(pts
				(arc
					(start 0 0.6096)
					(mid 0 -0.6096)
					(end 0 0.6096)
				)
			)
			(stroke
				(width 0)
				(type default)
			)
			(fill no)
			(layer "B.Fab")
		)
		(pad "1" smd circle
			(at 0 0 270)
			(size 0.7112 0.7112)
			(layers "B.Cu" "B.Mask" "B.Paste")
			(net "IOC_GPIO_21")
		)
	)
	(footprint ""
		(layer "B.Cu")
		(at 198.374 -23.749 180)
		(property "Reference" "R238"
			(at 0 0 0)
			(layer "B.SilkS")
			(hide yes)
			(effects
				(font
					(size 1.27 1.27)
				)
				(justify mirror)
			)
		)
		(property "Value" "150R2F-1-GP"
			(at -0.064008 -3.993896 180)
			(unlocked yes)
			(layer "B.Fab")
			(hide yes)
			(effects
				(font
					(size 1.016 1.016)
					(thickness 0.1524)
				)
				(justify mirror)
			)
		)
		(property "Device Type" "R402H16"
			(at -0.064008 -5.517896 180)
			(unlocked yes)
			(layer "B.Fab")
			(hide yes)
			(effects
				(font
					(size 1.016 1.016)
					(thickness 0.1524)
				)
				(justify mirror)
			)
		)
		(duplicate_pad_numbers_are_jumpers no)
		(fp_line
			(start 0.508 -0.9398)
			(end 0.508 0.9398)
			(stroke
				(width 0.1524)
				(type default)
			)
			(layer "B.SilkS")
		)
		(fp_line
			(start -0.508 -0.9398)
			(end 0.508 -0.9398)
			(stroke
				(width 0.1524)
				(type default)
			)
			(layer "B.SilkS")
		)
		(fp_rect
			(start 0.508 0.9398)
			(end -0.508 -0.9398)
			(stroke
				(width 0)
				(type default)
			)
			(fill no)
			(layer "B.CrtYd")
		)
		(fp_rect
			(start 0.508 0.9398)
			(end -0.508 -0.9398)
			(stroke
				(width 0)
				(type default)
			)
			(fill no)
			(layer "B.Fab")
		)
		(pad "1" smd custom
			(at 0 -0.4445)
			(size 0.1397 0.1397)
			(layers "B.Cu" "B.Mask" "B.Paste")
			(net "P3V3")
			(options
				(clearance outline)
				(anchor circle)
			)
			(primitives
				(gr_poly
					(pts
						(arc
							(start -0.1778 0.2794)
							(mid -0.249642 0.249642)
							(end -0.2794 0.1778)
						)
						(arc
							(start -0.2794 -0.1778)
							(mid -0.249642 -0.249642)
							(end -0.1778 -0.2794)
						)
						(arc
							(start 0.1778 -0.2794)
							(mid 0.249642 -0.249642)
							(end 0.2794 -0.1778)
						)
						(arc
							(start 0.2794 0.1778)
							(mid 0.249642 0.249642)
							(end 0.1778 0.2794)
						)
					)
					(width 0)
					(fill yes)
				)
			)
		)
		(pad "2" smd custom
			(at 0 0.4445)
			(size 0.1397 0.1397)
			(layers "B.Cu" "B.Mask" "B.Paste")
			(net "SYS_HB_LED_R")
			(options
				(clearance outline)
				(anchor circle)
			)
			(primitives
				(gr_poly
					(pts
						(arc
							(start -0.1778 0.2794)
							(mid -0.249642 0.249642)
							(end -0.2794 0.1778)
						)
						(arc
							(start -0.2794 -0.1778)
							(mid -0.249642 -0.249642)
							(end -0.1778 -0.2794)
						)
						(arc
							(start 0.1778 -0.2794)
							(mid 0.249642 -0.249642)
							(end 0.2794 -0.1778)
						)
						(arc
							(start 0.2794 0.1778)
							(mid 0.249642 0.249642)
							(end 0.1778 0.2794)
						)
					)
					(width 0)
					(fill yes)
				)
			)
		)
	)
	(footprint ""
		(layer "B.Cu")
		(at 38.592252 -109.59338 90)
		(property "Reference" "C563"
			(at 0 0 90)
			(layer "B.SilkS")
			(hide yes)
			(effects
				(font
					(size 1.27 1.27)
				)
				(justify mirror)
			)
		)
		(property "Value" "SC10U16V5KX-7-GP-U"
			(at 0.0762 -6.1214 90)
			(unlocked yes)
			(layer "B.Fab")
			(hide yes)
			(effects
				(font
					(size 1.016 1.016)
					(thickness 0.1524)
				)
				(justify mirror)
			)
		)
		(property "Device Type" "C805H58"
			(at 0.0762 -8.1534 90)
			(unlocked yes)
			(layer "B.Fab")
			(hide yes)
			(effects
				(font
					(size 1.016 1.016)
					(thickness 0.1524)
				)
				(justify mirror)
			)
		)
		(duplicate_pad_numbers_are_jumpers no)
		(fp_line
			(start -0.635 0)
			(end 0.635 0)
			(stroke
				(width 0.508)
				(type default)
			)
			(layer "B.SilkS")
		)
		(fp_rect
			(start 0.9652 1.778)
			(end -0.9652 -1.778)
			(stroke
				(width 0)
				(type default)
			)
			(fill no)
			(layer "B.CrtYd")
		)
		(fp_poly
			(pts
				(xy 0.9652 -1.778) (xy -0.9652 -1.778) (xy -0.9652 1.778) (xy 0.9652 1.778)
			)
			(stroke
				(width 0)
				(type default)
			)
			(fill no)
			(layer "B.Fab")
		)
		(pad "1" smd rect
			(at 0 -0.9652 270)
			(size 1.397 1.143)
			(layers "B.Cu" "B.Mask" "B.Paste")
			(net "P5V")
		)
		(pad "2" smd rect
			(at 0 0.9652 270)
			(size 1.397 1.143)
			(layers "B.Cu" "B.Mask" "B.Paste")
			(net "GND")
		)
	)
)
